# BARRELEYE_G2-FPDB_POST-PVT-X02-BOM-X05-20171123_Final.xls.xlsx — TLA (bom)
| FOXCONN TECHNOLOGY GROUP |  |  |  |  |  |  |  |  |  |
| BILL OF MATERIAL |  |  |  |  |  |  |  |  |  |
| AA P/N | 1A42G4V00-600-G | CUSTOMER | <name> | Customer P/N | N/A | Product Code |  |  |  |
| PWA P/N |  | PWA DESCRIPTION | Fan and power distribution board |  |  | PWA REV | PVT-X02 | Prepared By SE |  |
| Item | FOXCONN P/N | Customer P/N | Part Description | Manufacturer  Full Name | Manufacturer  Part Number | Qty | RoHS Status | Location | Remark |
| 1 | 7J-004-938 |  | L6 LABEL ( 12.7*11.1mm) | FOXCONN / EPD1 | 7J-004-938 | 1 | G |  | ID label for two boards. FPDB AA P/N: 1A42G4V00-600-G |
